# S9S_MB_2U (Grand Teton) — schematic netlist excerpt (pin names and nets, part order shuffled) for the footprints in the layout excerpt that follows; sources: Cadence DE-HDL packaged netlist, KiCad conversion of 03242023_DA0F0TMBIJ0_F0T_Motherboard_J_brd_V01_OCP.brd

PD15  ZENER_AC  5.0SMDJ14A IC  pkg D2723_SMCXC  page 304 : A = GND ; C = P12V_PSU_FUSE

(kicad_pcb
	(version 20260206)
	(generator "pcbnew")
	(generator_version "10.0")
	(general
		(thickness 1.6)
		(legacy_teardrops no)
	)
	(paper "A4")
	(title_block
		(title "03242023_DA0F0TMBIJ0_F0T_Motherboard_J_brd_V01_OCP.brd")
		(comment 1 "Grand Teton / footprints 4776-4776 of 6105")
	)
	(layers
		(0 "F.Cu" signal "TOP")
		(4 "In1.Cu" signal "GND")
		(6 "In2.Cu" signal "IN1")
		(8 "In3.Cu" signal "GND1")
		(10 "In4.Cu" signal "IN2")
		(12 "In5.Cu" signal "GND2")
		(14 "In6.Cu" signal "IN3")
		(16 "In7.Cu" signal "GND3")
		(18 "In8.Cu" signal "VCC")
		(20 "In9.Cu" signal "VCC1")
		(22 "In10.Cu" signal "GND4")
		(24 "In11.Cu" signal "IN4")
		(26 "In12.Cu" signal "GND5")
		(28 "In13.Cu" signal "IN5")
		(30 "In14.Cu" signal "GND6")
		(32 "In15.Cu" signal "IN6")
		(34 "In16.Cu" signal "GND7")
		(2 "B.Cu" signal "BOTTOM")
		(9 "F.Adhes" user "F.Adhesive")
		(11 "B.Adhes" user "B.Adhesive")
		(13 "F.Paste" user "Package Geometry/Pastemask Top")
		(15 "B.Paste" user "Package Geometry/Pastemask Bottom")
		(5 "F.SilkS" user "Ref Des/Silkscreen Top")
		(7 "B.SilkS" user "Ref Des/Silkscreen Bottom")
		(1 "F.Mask" user "Board Geometry/Soldermask Top")
		(3 "B.Mask" user "Board Geometry/Soldermask Bottom")
		(17 "Dwgs.User" user "User.Drawings")
		(19 "Cmts.User" user "User.Comments")
		(21 "Eco1.User" user "User.Eco1")
		(23 "Eco2.User" user "User.Eco2")
		(25 "Edge.Cuts" user "Board Geometry/Outline")
		(27 "Margin" user)
		(31 "F.CrtYd" user "Package Geometry/Place Bound Top")
		(29 "B.CrtYd" user "Package Geometry/Place Bound Bottom")
		(35 "F.Fab" user "Ref Des/Assembly Top")
		(33 "B.Fab" user "Ref Des/Assembly Bottom")
	)
	(footprint ""
		(layer "B.Cu")
		(at 256.631948 -419.142672 90)
		(property "Reference" "PD15"
			(at 4.7244 -3.851148 90)
			(unlocked yes)
			(layer "B.SilkS")
			(effects
				(font
					(size 0.7874 0.5842)
					(thickness 0.1524)
				)
				(justify left mirror)
			)
		)
		(property "Value" ""
			(at 0 0 90)
			(layer "B.Fab")
			(effects
				(font
					(size 1.27 1.27)
				)
				(justify mirror)
			)
		)
		(duplicate_pad_numbers_are_jumpers no)
		(fp_line
			(start 4.664456 -3.109976)
			(end -4.743704 -3.109976)
			(stroke
				(width 0.1524)
				(type default)
			)
			(layer "B.SilkS")
		)
		(fp_line
			(start -4.183126 -3.109976)
			(end -4.794504 -3.109976)
			(stroke
				(width 0.1524)
				(type default)
			)
			(layer "B.SilkS")
		)
		(fp_line
			(start -4.511802 -3.109976)
			(end -4.207002 -3.109976)
			(stroke
				(width 0.1524)
				(type default)
			)
			(layer "B.SilkS")
		)
		(fp_line
			(start -4.6101 -3.109976)
			(end -4.283202 -3.109976)
			(stroke
				(width 0.1524)
				(type default)
			)
			(layer "B.SilkS")
		)
		(fp_line
			(start -4.695444 -3.109976)
			(end -4.695444 3.109976)
			(stroke
				(width 0.1524)
				(type default)
			)
			(layer "B.SilkS")
		)
		(fp_line
			(start -4.70535 -3.109976)
			(end -4.70535 3.109976)
			(stroke
				(width 0.1524)
				(type default)
			)
			(layer "B.SilkS")
		)
		(fp_line
			(start -4.70535 -3.109976)
			(end -4.70535 3.109976)
			(stroke
				(width 0.1524)
				(type default)
			)
			(layer "B.SilkS")
		)
		(fp_line
			(start -4.70535 -3.109976)
			(end -4.70535 3.109976)
			(stroke
				(width 0.1524)
				(type default)
			)
			(layer "B.SilkS")
		)
		(fp_line
			(start -4.805426 -3.109976)
			(end -4.805426 3.109976)
			(stroke
				(width 0.1524)
				(type default)
			)
			(layer "B.SilkS")
		)
		(fp_line
			(start -4.932426 -3.109976)
			(end -4.932426 3.109976)
			(stroke
				(width 0.1524)
				(type default)
			)
			(layer "B.SilkS")
		)
		(fp_line
			(start -5.008626 -3.109976)
			(end -5.008626 3.109976)
			(stroke
				(width 0.1524)
				(type default)
			)
			(layer "B.SilkS")
		)
		(fp_line
			(start -5.110226 -3.109976)
			(end -5.110226 3.109976)
			(stroke
				(width 0.1524)
				(type default)
			)
			(layer "B.SilkS")
		)
		(fp_line
			(start -5.211826 -3.109976)
			(end -5.211826 3.109976)
			(stroke
				(width 0.1524)
				(type default)
			)
			(layer "B.SilkS")
		)
		(fp_line
			(start -5.262626 -3.109976)
			(end -5.262626 3.109976)
			(stroke
				(width 0.1524)
				(type default)
			)
			(layer "B.SilkS")
		)
		(fp_line
			(start -5.313426 -3.109976)
			(end -5.313426 3.109976)
			(stroke
				(width 0.1524)
				(type default)
			)
			(layer "B.SilkS")
		)
		(fp_line
			(start -5.4102 -3.109976)
			(end -4.783074 -3.109976)
			(stroke
				(width 0.1524)
				(type default)
			)
			(layer "B.SilkS")
		)
		(fp_line
			(start 0.508 -1.016)
			(end -0.762 0)
			(stroke
				(width 0.1524)
				(type default)
			)
			(layer "B.SilkS")
		)
		(fp_line
			(start 1.0668 0)
			(end 0.6096 0)
			(stroke
				(width 0.1524)
				(type default)
			)
			(layer "B.SilkS")
		)
		(fp_line
			(start -0.762 0)
			(end -1.2192 0)
			(stroke
				(width 0.1524)
				(type default)
			)
			(layer "B.SilkS")
		)
		(fp_line
			(start -0.762 0)
			(end 0.508 1.016)
			(stroke
				(width 0.1524)
				(type default)
			)
			(layer "B.SilkS")
		)
		(fp_line
			(start 0.508 1.016)
			(end 0.508 -1.016)
			(stroke
				(width 0.1524)
				(type default)
			)
			(layer "B.SilkS")
		)
		(fp_line
			(start -0.762 1.27)
			(end -0.762 -1.27)
			(stroke
				(width 0.1524)
				(type default)
			)
			(layer "B.SilkS")
		)
		(fp_line
			(start -4.715002 3.035554)
			(end -4.7117 2.984754)
			(stroke
				(width 0.1524)
				(type default)
			)
			(layer "B.SilkS")
		)
		(fp_line
			(start 4.664456 3.109976)
			(end 4.664456 -3.109976)
			(stroke
				(width 0.1524)
				(type default)
			)
			(layer "B.SilkS")
		)
		(fp_line
			(start -4.156202 3.109976)
			(end -4.183126 3.109976)
			(stroke
				(width 0.1524)
				(type default)
			)
			(layer "B.SilkS")
		)
		(fp_line
			(start -4.743704 3.109976)
			(end -4.6101 3.109976)
			(stroke
				(width 0.1524)
				(type default)
			)
			(layer "B.SilkS")
		)
		(fp_line
			(start -4.743704 3.109976)
			(end -5.4102 3.109976)
			(stroke
				(width 0.1524)
				(type default)
			)
			(layer "B.SilkS")
		)
		(fp_line
			(start -4.769104 3.109976)
			(end 4.664456 3.109976)
			(stroke
				(width 0.1524)
				(type default)
			)
			(layer "B.SilkS")
		)
		(fp_line
			(start -4.794504 3.109976)
			(end -3.554984 3.109976)
			(stroke
				(width 0.1524)
				(type default)
			)
			(layer "B.SilkS")
		)
		(fp_line
			(start -5.4102 3.109976)
			(end -5.4102 -3.109976)
			(stroke
				(width 0.1524)
				(type default)
			)
			(layer "B.SilkS")
		)
		(fp_line
			(start 4.065016 -3.109976)
			(end -4.065016 -3.109976)
			(stroke
				(width 0.1)
				(type default)
			)
			(layer "B.Fab")
		)
		(fp_line
			(start -4.065016 -3.109976)
			(end -4.065016 3.109976)
			(stroke
				(width 0.1)
				(type default)
			)
			(layer "B.Fab")
		)
		(fp_line
			(start 4.065016 3.109976)
			(end 4.065016 -3.109976)
			(stroke
				(width 0.1)
				(type default)
			)
			(layer "B.Fab")
		)
		(fp_line
			(start -4.065016 3.109976)
			(end 4.065016 3.109976)
			(stroke
				(width 0.1)
				(type default)
			)
			(layer "B.Fab")
		)
		(fp_text user "+"
			(at 4.5974 0.24765 270)
			(unlocked yes)
			(layer "B.SilkS")
			(effects
				(font
					(size 1.905 1.4224)
					(thickness 0.1524)
				)
				(justify left mirror)
			)
		)
		(fp_text user "-"
			(at -6.643624 0.40005 270)
			(unlocked yes)
			(layer "B.SilkS")
			(effects
				(font
					(size 1.905 1.4224)
					(thickness 0.1524)
				)
				(justify left mirror)
			)
		)
		(fp_text user "+"
			(at 4.5974 0.24765 270)
			(unlocked yes)
			(layer "B.Fab")
			(effects
				(font
					(size 1.905 1.4224)
					(thickness 0.1524)
				)
				(justify left mirror)
			)
		)
		(fp_text user "-"
			(at -6.643624 0.40005 270)
			(unlocked yes)
			(layer "B.Fab")
			(effects
				(font
					(size 1.905 1.4224)
					(thickness 0.1524)
				)
				(justify left mirror)
			)
		)
		(pad "A" smd rect
			(at 3.299968 0 90)
			(size 2.413 3.302)
			(layers "B.Cu" "B.Mask" "B.Paste")
			(net "GND")
		)
		(pad "C" smd rect
			(at -3.299968 0 90)
			(size 2.413 3.302)
			(layers "B.Cu" "B.Mask" "B.Paste")
			(net "P12V_PSU_FUSE")
		)
	)
)
